# SCM (Grand Teton) — schematic netlist excerpt (pin names and nets, part order shuffled) for the footprints in the layout excerpt that follows; sources: Cadence DE-HDL packaged netlist, KiCad conversion of 12092022_DA0F0TMDCD0_F0T_Management_Board_D_brd_V3_OCP.brd

R118  Q_RES  100K 1% CHIP  pkg 0402LF  page 12 : A = GND ; B = RST_PLTRST_N

(kicad_pcb
	(version 20260206)
	(generator "pcbnew")
	(generator_version "10.0")
	(general
		(thickness 1.6)
		(legacy_teardrops no)
	)
	(paper "A4")
	(title_block
		(title "12092022_DA0F0TMDCD0_F0T_Management_Board_D_brd_V3_OCP.brd")
		(comment 1 "Grand Teton / footprints 649-649 of 1440")
	)
	(layers
		(0 "F.Cu" signal "TOP")
		(4 "In1.Cu" signal "GND")
		(6 "In2.Cu" signal "IN1")
		(8 "In3.Cu" signal "GND1")
		(10 "In4.Cu" signal "IN2")
		(12 "In5.Cu" signal "VCC")
		(14 "In6.Cu" signal "VCC1")
		(16 "In7.Cu" signal "IN3")
		(18 "In8.Cu" signal "GND2")
		(20 "In9.Cu" signal "IN4")
		(22 "In10.Cu" signal "GND3")
		(2 "B.Cu" signal "BOTTOM")
		(9 "F.Adhes" user "F.Adhesive")
		(11 "B.Adhes" user "B.Adhesive")
		(13 "F.Paste" user "Package Geometry/Pastemask Top")
		(15 "B.Paste" user "Package Geometry/Pastemask Bottom")
		(5 "F.SilkS" user "Ref Des/Silkscreen Top")
		(7 "B.SilkS" user "Ref Des/Silkscreen Bottom")
		(1 "F.Mask" user "Board Geometry/Soldermask Top")
		(3 "B.Mask" user "Board Geometry/Soldermask Bottom")
		(17 "Dwgs.User" user "User.Drawings")
		(19 "Cmts.User" user "User.Comments")
		(21 "Eco1.User" user "User.Eco1")
		(23 "Eco2.User" user "User.Eco2")
		(25 "Edge.Cuts" user "Board Geometry/Outline")
		(27 "Margin" user)
		(31 "F.CrtYd" user "Package Geometry/Place Bound Top")
		(29 "B.CrtYd" user "Package Geometry/Place Bound Bottom")
		(35 "F.Fab" user "Ref Des/Assembly Top")
		(33 "B.Fab" user "Ref Des/Assembly Bottom")
	)
	(footprint ""
		(layer "F.Cu")
		(at 61.51753 -34.637726 90)
		(property "Reference" "R118"
			(at 0 0 90)
			(layer "F.SilkS")
			(hide yes)
			(effects
				(font
					(size 1.27 1.27)
				)
			)
		)
		(property "Value" ""
			(at 0 0 90)
			(layer "F.Fab")
			(effects
				(font
					(size 1.27 1.27)
				)
			)
		)
		(duplicate_pad_numbers_are_jumpers no)
		(fp_line
			(start 0.7874 -0.4064)
			(end 0.7874 0.4064)
			(stroke
				(width 0.1524)
				(type default)
			)
			(layer "F.SilkS")
		)
		(fp_line
			(start -0.7874 -0.4064)
			(end 0.7874 -0.4064)
			(stroke
				(width 0.1524)
				(type default)
			)
			(layer "F.SilkS")
		)
		(fp_line
			(start 0.7874 0.4064)
			(end -0.7874 0.4064)
			(stroke
				(width 0.1524)
				(type default)
			)
			(layer "F.SilkS")
		)
		(fp_line
			(start -0.7874 0.4064)
			(end -0.7874 -0.4064)
			(stroke
				(width 0.1524)
				(type default)
			)
			(layer "F.SilkS")
		)
		(fp_line
			(start -0.12065 -0.305054)
			(end -0.12065 -0.2794)
			(stroke
				(width 0.1)
				(type default)
			)
			(layer "F.Fab")
		)
		(fp_line
			(start -0.67945 -0.305054)
			(end -0.12065 -0.305054)
			(stroke
				(width 0.1)
				(type default)
			)
			(layer "F.Fab")
		)
		(fp_line
			(start 0.67945 -0.3048)
			(end 0.67945 0.3048)
			(stroke
				(width 0.1)
				(type default)
			)
			(layer "F.Fab")
		)
		(fp_line
			(start 0.12065 -0.3048)
			(end 0.67945 -0.3048)
			(stroke
				(width 0.1)
				(type default)
			)
			(layer "F.Fab")
		)
		(fp_line
			(start 0.12065 -0.2794)
			(end 0.12065 -0.3048)
			(stroke
				(width 0.1)
				(type default)
			)
			(layer "F.Fab")
		)
		(fp_line
			(start -0.12065 -0.2794)
			(end 0.12065 -0.2794)
			(stroke
				(width 0.1)
				(type default)
			)
			(layer "F.Fab")
		)
		(fp_line
			(start 0.120396 0.2794)
			(end -0.12065 0.2794)
			(stroke
				(width 0.1)
				(type default)
			)
			(layer "F.Fab")
		)
		(fp_line
			(start -0.12065 0.2794)
			(end -0.12065 0.3048)
			(stroke
				(width 0.1)
				(type default)
			)
			(layer "F.Fab")
		)
		(fp_line
			(start 0.67945 0.3048)
			(end 0.120396 0.3048)
			(stroke
				(width 0.1)
				(type default)
			)
			(layer "F.Fab")
		)
		(fp_line
			(start 0.120396 0.3048)
			(end 0.120396 0.2794)
			(stroke
				(width 0.1)
				(type default)
			)
			(layer "F.Fab")
		)
		(fp_line
			(start -0.12065 0.3048)
			(end -0.67945 0.3048)
			(stroke
				(width 0.1)
				(type default)
			)
			(layer "F.Fab")
		)
		(fp_line
			(start -0.67945 0.3048)
			(end -0.67945 -0.305054)
			(stroke
				(width 0.1)
				(type default)
			)
			(layer "F.Fab")
		)
		(pad "1" smd circle
			(at -0.40005 0 90)
			(size 0 0)
			(layers "F.Cu" "F.Mask" "F.Paste")
			(net "GND")
		)
		(pad "2" smd circle
			(at 0.40005 0 90)
			(size 0 0)
			(layers "F.Cu" "F.Mask" "F.Paste")
			(net "RST_PLTRST_N")
		)
	)
)
